(kicad_pcb
	(version 20260206)
	(generator "pcbnew")
	(generator_version "10.0")
	(general
		(thickness 1.6)
		(legacy_teardrops no)
	)
	(paper "A4")
	(title_block
		(title "01162023_DA0F0TEBIF0_F0T_Expander_BD_F_brd_V02_OCP.brd")
		(comment 1 "Grand Teton / footprints 4741-4742 of 9728")
	)
	(layers
		(0 "F.Cu" signal "TOP")
		(4 "In1.Cu" signal "GND")
		(6 "In2.Cu" signal "VCC")
		(8 "In3.Cu" signal "VCC1")
		(10 "In4.Cu" signal "GND1")
		(12 "In5.Cu" signal "IN1")
		(14 "In6.Cu" signal "GND2")
		(16 "In7.Cu" signal "IN2")
		(18 "In8.Cu" signal "GND3")
		(20 "In9.Cu" signal "IN3")
		(22 "In10.Cu" signal "GND4")
		(24 "In11.Cu" signal "IN4")
		(26 "In12.Cu" signal "GND5")
		(28 "In13.Cu" signal "IN5")
		(30 "In14.Cu" signal "GND6")
		(32 "In15.Cu" signal "IN6")
		(34 "In16.Cu" signal "GND7")
		(2 "B.Cu" signal "BOTTOM")
		(9 "F.Adhes" user "F.Adhesive")
		(11 "B.Adhes" user "B.Adhesive")
		(13 "F.Paste" user "Package Geometry/Pastemask Top")
		(15 "B.Paste" user "Package Geometry/Pastemask Bottom")
		(5 "F.SilkS" user "Ref Des/Silkscreen Top")
		(7 "B.SilkS" user "Ref Des/Silkscreen Bottom")
		(1 "F.Mask" user "Board Geometry/Soldermask Top")
		(3 "B.Mask" user "Board Geometry/Soldermask Bottom")
		(17 "Dwgs.User" user "User.Drawings")
		(19 "Cmts.User" user "User.Comments")
		(21 "Eco1.User" user "User.Eco1")
		(23 "Eco2.User" user "User.Eco2")
		(25 "Edge.Cuts" user "Board Geometry/Outline")
		(27 "Margin" user)
		(31 "F.CrtYd" user "Package Geometry/Place Bound Top")
		(29 "B.CrtYd" user "Package Geometry/Place Bound Bottom")
		(35 "F.Fab" user "Ref Des/Assembly Top")
		(33 "B.Fab" user "Ref Des/Assembly Bottom")
	)
	(footprint ""
		(layer "F.Cu")
		(at 90.964766 -26.785062 180)
		(property "Reference" "J33"
			(at 3.892296 -11.037062 90)
			(unlocked yes)
			(layer "F.SilkS")
			(effects
				(font
					(size 0.7874 0.5842)
					(thickness 0.1524)
				)
			)
		)
		(property "Value" ""
			(at 0 0 180)
			(layer "F.Fab")
			(effects
				(font
					(size 1.27 1.27)
				)
			)
		)
		(duplicate_pad_numbers_are_jumpers no)
		(fp_line
			(start 3.150108 12.115038)
			(end 1.529334 12.115038)
			(stroke
				(width 0.1524)
				(type default)
			)
			(layer "F.SilkS")
		)
		(fp_line
			(start 3.074924 12.014962)
			(end 1.632204 12.014962)
			(stroke
				(width 0.1524)
				(type default)
			)
			(layer "F.SilkS")
		)
		(fp_line
			(start 1.632204 -12.014962)
			(end 3.074924 -12.014962)
			(stroke
				(width 0.1524)
				(type default)
			)
			(layer "F.SilkS")
		)
		(fp_line
			(start 1.529334 -12.115038)
			(end 3.150108 -12.115038)
			(stroke
				(width 0.1524)
				(type default)
			)
			(layer "F.SilkS")
		)
		(fp_line
			(start -1.529334 12.115038)
			(end -3.150108 12.115038)
			(stroke
				(width 0.1524)
				(type default)
			)
			(layer "F.SilkS")
		)
		(fp_line
			(start -1.632204 12.014962)
			(end -3.074924 12.014962)
			(stroke
				(width 0.1524)
				(type default)
			)
			(layer "F.SilkS")
		)
		(fp_line
			(start -3.074924 -12.014962)
			(end -1.632204 -12.014962)
			(stroke
				(width 0.1524)
				(type default)
			)
			(layer "F.SilkS")
		)
		(fp_line
			(start -3.150108 -12.115038)
			(end -1.529334 -12.115038)
			(stroke
				(width 0.1524)
				(type default)
			)
			(layer "F.SilkS")
		)
		(fp_poly
			(pts
				(xy 3.341116 -8.698738) (xy 3.763518 -9.966452) (xy 4.608576 -9.121394)
			)
			(stroke
				(width 0)
				(type default)
			)
			(fill yes)
			(layer "F.SilkS")
		)
		(fp_line
			(start 3.074924 12.014962)
			(end -3.074924 12.014962)
			(stroke
				(width 0.1)
				(type default)
			)
			(layer "F.Fab")
		)
		(fp_line
			(start 3.074924 -12.014962)
			(end 3.074924 12.014962)
			(stroke
				(width 0.1)
				(type default)
			)
			(layer "F.Fab")
		)
		(fp_line
			(start -3.074924 12.014962)
			(end -3.074924 -12.014962)
			(stroke
				(width 0.1)
				(type default)
			)
			(layer "F.Fab")
		)
		(fp_line
			(start -3.074924 -12.014962)
			(end 3.074924 -12.014962)
			(stroke
				(width 0.1)
				(type default)
			)
			(layer "F.Fab")
		)
		(fp_poly
			(pts
				(xy 3.348736 -7.994904) (xy 4.543806 -8.592566) (xy 4.543806 -7.397496)
			)
			(stroke
				(width 0)
				(type default)
			)
			(fill yes)
			(layer "F.Fab")
		)
		(pad "" np_thru_hole circle
			(at -1.75006 -9.815068 90)
			(size 1.1176 1.1176)
			(drill 1.1176)
			(layers "*.Cu" "*.Mask")
			(clearance 0.381)
			(thermal_gap 0.381)
		)
		(pad "" np_thru_hole circle
			(at 0 9.815068 90)
			(size 1.1176 1.1176)
			(drill 1.1176)
			(layers "*.Cu" "*.Mask")
			(clearance 0.381)
			(thermal_gap 0.381)
		)
		(pad "A1" smd rect
			(at 2.29997 -7.994904 90)
			(size 0.381 1.27)
			(layers "F.Cu" "F.Mask" "F.Paste")
			(net "GND")
		)
		(pad "A2" smd rect
			(at 2.29997 -7.394956 90)
			(size 0.381 1.27)
			(layers "F.Cu" "F.Mask" "F.Paste")
			(net "GND")
		)
		(pad "A3" smd rect
			(at 2.29997 -6.795008 90)
			(size 0.381 1.27)
			(layers "F.Cu" "F.Mask" "F.Paste")
			(net "GND")
		)
		(pad "A4" smd rect
			(at 2.29997 -6.19506 90)
			(size 0.381 1.27)
			(layers "F.Cu" "F.Mask" "F.Paste")
			(net "GND")
		)
		(pad "A5" smd rect
			(at 2.29997 -5.595112 90)
			(size 0.381 1.27)
			(layers "F.Cu" "F.Mask" "F.Paste")
			(net "GND")
		)
		(pad "A6" smd rect
			(at 2.29997 -4.99491 90)
			(size 0.381 1.27)
			(layers "F.Cu" "F.Mask" "F.Paste")
			(net "GND")
		)
		(pad "A7" smd rect
			(at 2.29997 -4.394962 90)
			(size 0.381 1.27)
			(layers "F.Cu" "F.Mask" "F.Paste")
			(net "SMB_ISO_SSD3_R_SCL")
		)
		(pad "A8" smd rect
			(at 2.29997 -3.795014 90)
			(size 0.381 1.27)
			(layers "F.Cu" "F.Mask" "F.Paste")
			(net "SMB_ISO_SSD3_R_SDA")
		)
		(pad "A9" smd rect
			(at 2.29997 -3.195066 90)
			(size 0.381 1.27)
			(layers "F.Cu" "F.Mask" "F.Paste")
			(net "RST_SMB_SSD3_ISO_R_N")
		)
		(pad "A10" smd rect
			(at 2.29997 -2.595118 90)
			(size 0.381 1.27)
			(layers "F.Cu" "F.Mask" "F.Paste")
			(net "SSD3_LED_ISO_R_N")
		)
		(pad "A11" smd rect
			(at 2.29997 -1.994916 90)
			(size 0.381 1.27)
			(layers "F.Cu" "F.Mask" "F.Paste")
			(net "PU_CLKREQ3")
		)
		(pad "A12" smd rect
			(at 2.29997 -1.394968 90)
			(size 0.381 1.27)
			(layers "F.Cu" "F.Mask" "F.Paste")
			(net "PRSNT_SSD3_N")
		)
		(pad "A13" smd rect
			(at 2.29997 -0.79502 90)
			(size 0.381 1.27)
			(layers "F.Cu" "F.Mask" "F.Paste")
			(net "GND")
		)
		(pad "A14" smd rect
			(at 2.29997 -0.195072 90)
			(size 0.381 1.27)
			(layers "F.Cu" "F.Mask" "F.Paste")
			(net "Net_8567")
		)
		(pad "A15" smd rect
			(at 2.29997 0.404876 90)
			(size 0.381 1.27)
			(layers "F.Cu" "F.Mask" "F.Paste")
			(net "Net_8566")
		)
		(pad "A16" smd rect
			(at 2.29997 1.005078 90)
			(size 0.381 1.27)
			(layers "F.Cu" "F.Mask" "F.Paste")
			(net "GND")
		)
		(pad "A17" smd rect
			(at 2.29997 1.605026 90)
			(size 0.381 1.27)
			(layers "F.Cu" "F.Mask" "F.Paste")
			(net "P5E_PEX0_STN2_RX_DN<32>")
		)
		(pad "A18" smd rect
			(at 2.29997 2.204974 90)
			(size 0.381 1.27)
			(layers "F.Cu" "F.Mask" "F.Paste")
			(net "P5E_PEX0_STN2_RX_DP<32>")
		)
		(pad "A19" smd rect
			(at 2.29997 2.804922 90)
			(size 0.381 1.27)
			(layers "F.Cu" "F.Mask" "F.Paste")
			(net "GND")
		)
		(pad "A20" smd rect
			(at 2.29997 3.405124 90)
			(size 0.381 1.27)
			(layers "F.Cu" "F.Mask" "F.Paste")
			(net "P5E_PEX0_STN2_RX_DN<33>")
		)
		(pad "A21" smd rect
			(at 2.29997 4.005072 90)
			(size 0.381 1.27)
			(layers "F.Cu" "F.Mask" "F.Paste")
			(net "P5E_PEX0_STN2_RX_DP<33>")
		)
		(pad "A22" smd rect
			(at 2.29997 4.60502 90)
			(size 0.381 1.27)
			(layers "F.Cu" "F.Mask" "F.Paste")
			(net "GND")
		)
		(pad "A23" smd rect
			(at 2.29997 5.204968 90)
			(size 0.381 1.27)
			(layers "F.Cu" "F.Mask" "F.Paste")
			(net "P5E_PEX0_STN2_RX_DN<34>")
		)
		(pad "A24" smd rect
			(at 2.29997 5.804916 90)
			(size 0.381 1.27)
			(layers "F.Cu" "F.Mask" "F.Paste")
			(net "P5E_PEX0_STN2_RX_DP<34>")
		)
		(pad "A25" smd rect
			(at 2.29997 6.405118 90)
			(size 0.381 1.27)
			(layers "F.Cu" "F.Mask" "F.Paste")
			(net "GND")
		)
		(pad "A26" smd rect
			(at 2.29997 7.005066 90)
			(size 0.381 1.27)
			(layers "F.Cu" "F.Mask" "F.Paste")
			(net "P5E_PEX0_STN2_RX_DN<35>")
		)
		(pad "A27" smd rect
			(at 2.29997 7.605014 90)
			(size 0.381 1.27)
			(layers "F.Cu" "F.Mask" "F.Paste")
			(net "P5E_PEX0_STN2_RX_DP<35>")
		)
		(pad "A28" smd rect
			(at 2.29997 8.204962 90)
			(size 0.381 1.27)
			(layers "F.Cu" "F.Mask" "F.Paste")
			(net "GND")
		)
		(pad "B1" smd rect
			(at -2.29997 -7.994904 90)
			(size 0.381 1.27)
			(layers "F.Cu" "F.Mask" "F.Paste")
			(net "P12V_SSD3")
		)
		(pad "B2" smd rect
			(at -2.29997 -7.394956 90)
			(size 0.381 1.27)
			(layers "F.Cu" "F.Mask" "F.Paste")
			(net "P12V_SSD3")
		)
		(pad "B3" smd rect
			(at -2.29997 -6.795008 90)
			(size 0.381 1.27)
			(layers "F.Cu" "F.Mask" "F.Paste")
			(net "P12V_SSD3")
		)
		(pad "B4" smd rect
			(at -2.29997 -6.19506 90)
			(size 0.381 1.27)
			(layers "F.Cu" "F.Mask" "F.Paste")
			(net "P12V_SSD3")
		)
		(pad "B5" smd rect
			(at -2.29997 -5.595112 90)
			(size 0.381 1.27)
			(layers "F.Cu" "F.Mask" "F.Paste")
			(net "P12V_SSD3")
		)
		(pad "B6" smd rect
			(at -2.29997 -4.99491 90)
			(size 0.381 1.27)
			(layers "F.Cu" "F.Mask" "F.Paste")
			(net "P12V_SSD3")
		)
		(pad "B7" smd rect
			(at -2.29997 -4.394962 90)
			(size 0.381 1.27)
			(layers "F.Cu" "F.Mask" "F.Paste")
			(net "Net_8568")
		)
		(pad "B8" smd rect
			(at -2.29997 -3.795014 90)
			(size 0.381 1.27)
			(layers "F.Cu" "F.Mask" "F.Paste")
			(net "Net_8565")
		)
		(pad "B9" smd rect
			(at -2.29997 -3.195066 90)
			(size 0.381 1.27)
			(layers "F.Cu" "F.Mask" "F.Paste")
			(net "DUALPORT_N_SSD3")
		)
		(pad "B10" smd rect
			(at -2.29997 -2.595118 90)
			(size 0.381 1.27)
			(layers "F.Cu" "F.Mask" "F.Paste")
			(net "RST_SSD3_PERST_R_N")
		)
		(pad "B11" smd rect
			(at -2.29997 -1.994916 90)
			(size 0.381 1.27)
			(layers "F.Cu" "F.Mask" "F.Paste")
			(net "P3V3_SSD3")
		)
		(pad "B12" smd rect
			(at -2.29997 -1.394968 90)
			(size 0.381 1.27)
			(layers "F.Cu" "F.Mask" "F.Paste")
			(net "SSD3_PWRDIS_R")
		)
		(pad "B13" smd rect
			(at -2.29997 -0.79502 90)
			(size 0.381 1.27)
			(layers "F.Cu" "F.Mask" "F.Paste")
			(net "GND")
		)
		(pad "B14" smd rect
			(at -2.29997 -0.195072 90)
			(size 0.381 1.27)
			(layers "F.Cu" "F.Mask" "F.Paste")
			(net "CLK_100M_DB800ZL_SSD3_R_DN")
		)
		(pad "B15" smd rect
			(at -2.29997 0.404876 90)
			(size 0.381 1.27)
			(layers "F.Cu" "F.Mask" "F.Paste")
			(net "CLK_100M_DB800ZL_SSD3_R_DP")
		)
		(pad "B16" smd rect
			(at -2.29997 1.005078 90)
			(size 0.381 1.27)
			(layers "F.Cu" "F.Mask" "F.Paste")
			(net "GND")
		)
		(pad "B17" smd rect
			(at -2.29997 1.605026 90)
			(size 0.381 1.27)
			(layers "F.Cu" "F.Mask" "F.Paste")
			(net "P5E_PEX0_STN2_TX_C_DN<32>")
		)
		(pad "B18" smd rect
			(at -2.29997 2.204974 90)
			(size 0.381 1.27)
			(layers "F.Cu" "F.Mask" "F.Paste")
			(net "P5E_PEX0_STN2_TX_C_DP<32>")
		)
		(pad "B19" smd rect
			(at -2.29997 2.804922 90)
			(size 0.381 1.27)
			(layers "F.Cu" "F.Mask" "F.Paste")
			(net "GND")
		)
		(pad "B20" smd rect
			(at -2.29997 3.405124 90)
			(size 0.381 1.27)
			(layers "F.Cu" "F.Mask" "F.Paste")
			(net "P5E_PEX0_STN2_TX_C_DN<33>")
		)
		(pad "B21" smd rect
			(at -2.29997 4.005072 90)
			(size 0.381 1.27)
			(layers "F.Cu" "F.Mask" "F.Paste")
			(net "P5E_PEX0_STN2_TX_C_DP<33>")
		)
		(pad "B22" smd rect
			(at -2.29997 4.60502 90)
			(size 0.381 1.27)
			(layers "F.Cu" "F.Mask" "F.Paste")
			(net "GND")
		)
		(pad "B23" smd rect
			(at -2.29997 5.204968 90)
			(size 0.381 1.27)
			(layers "F.Cu" "F.Mask" "F.Paste")
			(net "P5E_PEX0_STN2_TX_C_DN<34>")
		)
		(pad "B24" smd rect
			(at -2.29997 5.804916 90)
			(size 0.381 1.27)
			(layers "F.Cu" "F.Mask" "F.Paste")
			(net "P5E_PEX0_STN2_TX_C_DP<34>")
		)
		(pad "B25" smd rect
			(at -2.29997 6.405118 90)
			(size 0.381 1.27)
			(layers "F.Cu" "F.Mask" "F.Paste")
			(net "GND")
		)
		(pad "B26" smd rect
			(at -2.29997 7.005066 90)
			(size 0.381 1.27)
			(layers "F.Cu" "F.Mask" "F.Paste")
			(net "P5E_PEX0_STN2_TX_C_DN<35>")
		)
		(pad "B27" smd rect
			(at -2.29997 7.605014 90)
			(size 0.381 1.27)
			(layers "F.Cu" "F.Mask" "F.Paste")
			(net "P5E_PEX0_STN2_TX_C_DP<35>")
		)
		(pad "B28" smd rect
			(at -2.29997 8.204962 90)
			(size 0.381 1.27)
			(layers "F.Cu" "F.Mask" "F.Paste")
			(net "GND")
		)
		(pad "G1" thru_hole oval
			(at 0 -11.364976 90)
			(size 1.6256 3.4798)
			(drill oval 1.1176 2.4638)
			(layers "*.Cu" "*.Mask")
			(remove_unused_layers no)
			(net "GND")
			(clearance 0.127)
			(thermal_gap 0.127)
		)
		(pad "G2" thru_hole oval
			(at 0 11.364976 90)
			(size 1.6256 3.4798)
			(drill oval 1.1176 2.4638)
			(layers "*.Cu" "*.Mask")
			(remove_unused_layers no)
			(net "GND")
			(clearance 0.127)
			(thermal_gap 0.127)
		)
		(zone
			(layer "F.Cu")
			(hatch none 0.5)
			(connect_pads
				(clearance 0)
			)
			(min_thickness 0.25)
			(keepout
				(tracks not_allowed)
				(vias allowed)
				(pads allowed)
				(copperpour not_allowed)
				(footprints allowed)
			)
			(placement
				(enabled no)
				(sheetname "")
			)
			(fill
				(thermal_gap 0.5)
				(thermal_bridge_width 0.5)
				(island_removal_mode 0)
			)
			(polygon
				(pts
					(xy 92.344748 -38.850062) (xy 89.59469 -38.850062) (xy 89.59469 -35.900106) (xy 92.344748 -35.900106)
				)
			)
		)
		(zone
			(layer "F.Cu")
			(hatch none 0.5)
			(connect_pads
				(clearance 0)
			)
			(min_thickness 0.25)
			(keepout
				(tracks not_allowed)
				(vias allowed)
				(pads allowed)
				(copperpour not_allowed)
				(footprints allowed)
			)
			(placement
				(enabled no)
				(sheetname "")
			)
			(fill
				(thermal_gap 0.5)
				(thermal_bridge_width 0.5)
				(island_removal_mode 0)
			)
			(polygon
				(pts
					(xy 93.41485 -17.670018) (xy 89.584784 -17.670018) (xy 89.584784 -14.720062) (xy 93.41485 -14.720062)
				)
			)
		)
		(zone
			(layers "F.Cu" "B.Cu" "In1.Cu" "In2.Cu" "In3.Cu" "In4.Cu" "In5.Cu" "In6.Cu"
				"In7.Cu" "In8.Cu" "In9.Cu" "In10.Cu" "In11.Cu" "In12.Cu" "In13.Cu" "In14.Cu"
				"In15.Cu" "In16.Cu"
			)
			(hatch none 0.5)
			(connect_pads
				(clearance 0)
			)
			(min_thickness 0.25)
			(keepout
				(tracks not_allowed)
				(vias allowed)
				(pads allowed)
				(copperpour not_allowed)
				(footprints allowed)
			)
			(placement
				(enabled no)
				(sheetname "")
			)
			(fill
				(thermal_gap 0.5)
				(thermal_bridge_width 0.5)
				(island_removal_mode 0)
			)
			(polygon
				(pts
					(arc
						(start 91.929966 -36.60013)
						(mid 89.999566 -36.60013)
						(end 91.929966 -36.60013)
					)
				)
			)
		)
		(zone
			(layers "F.Cu" "B.Cu" "In1.Cu" "In2.Cu" "In3.Cu" "In4.Cu" "In5.Cu" "In6.Cu"
				"In7.Cu" "In8.Cu" "In9.Cu" "In10.Cu" "In11.Cu" "In12.Cu" "In13.Cu" "In14.Cu"
				"In15.Cu" "In16.Cu"
			)
			(hatch none 0.5)
			(connect_pads
				(clearance 0)
			)
			(min_thickness 0.25)
			(keepout
				(tracks not_allowed)
				(vias allowed)
				(pads allowed)
				(copperpour not_allowed)
				(footprints allowed)
			)
			(placement
				(enabled no)
				(sheetname "")
			)
			(fill
				(thermal_gap 0.5)
				(thermal_bridge_width 0.5)
				(island_removal_mode 0)
			)
			(polygon
				(pts
					(arc
						(start 93.680026 -16.969994)
						(mid 91.749626 -16.969994)
						(end 93.680026 -16.969994)
					)
				)
			)
		)
	)
	(footprint ""
		(layer "F.Cu")
		(at 233.839512 -234.728004 -90)
		(property "Reference" "R6191"
			(at 0 0 270)
			(layer "F.SilkS")
			(hide yes)
			(effects
				(font
					(size 1.27 1.27)
				)
			)
		)
		(property "Value" ""
			(at 0 0 270)
			(layer "F.Fab")
			(effects
				(font
					(size 1.27 1.27)
				)
			)
		)
		(duplicate_pad_numbers_are_jumpers no)
		(fp_line
			(start -0.7874 0.4064)
			(end -0.7874 -0.4064)
			(stroke
				(width 0.1524)
				(type default)
			)
			(layer "F.SilkS")
		)
		(fp_line
			(start 0.7874 0.4064)
			(end -0.7874 0.4064)
			(stroke
				(width 0.1524)
				(type default)
			)
			(layer "F.SilkS")
		)
		(fp_line
			(start -0.7874 -0.4064)
			(end 0.7874 -0.4064)
			(stroke
				(width 0.1524)
				(type default)
			)
			(layer "F.SilkS")
		)
		(fp_line
			(start 0.7874 -0.4064)
			(end 0.7874 0.4064)
			(stroke
				(width 0.1524)
				(type default)
			)
			(layer "F.SilkS")
		)
		(fp_line
			(start -0.67945 0.3048)
			(end -0.67945 -0.305054)
			(stroke
				(width 0.1)
				(type default)
			)
			(layer "F.Fab")
		)
		(fp_line
			(start -0.12065 0.3048)
			(end -0.67945 0.3048)
			(stroke
				(width 0.1)
				(type default)
			)
			(layer "F.Fab")
		)
		(fp_line
			(start 0.120396 0.3048)
			(end 0.120396 0.2794)
			(stroke
				(width 0.1)
				(type default)
			)
			(layer "F.Fab")
		)
		(fp_line
			(start 0.67945 0.3048)
			(end 0.120396 0.3048)
			(stroke
				(width 0.1)
				(type default)
			)
			(layer "F.Fab")
		)
		(fp_line
			(start -0.12065 0.2794)
			(end -0.12065 0.3048)
			(stroke
				(width 0.1)
				(type default)
			)
			(layer "F.Fab")
		)
		(fp_line
			(start 0.120396 0.2794)
			(end -0.12065 0.2794)
			(stroke
				(width 0.1)
				(type default)
			)
			(layer "F.Fab")
		)
		(fp_line
			(start -0.12065 -0.2794)
			(end 0.12065 -0.2794)
			(stroke
				(width 0.1)
				(type default)
			)
			(layer "F.Fab")
		)
		(fp_line
			(start 0.12065 -0.2794)
			(end 0.12065 -0.3048)
			(stroke
				(width 0.1)
				(type default)
			)
			(layer "F.Fab")
		)
		(fp_line
			(start 0.12065 -0.3048)
			(end 0.67945 -0.3048)
			(stroke
				(width 0.1)
				(type default)
			)
			(layer "F.Fab")
		)
		(fp_line
			(start 0.67945 -0.3048)
			(end 0.67945 0.3048)
			(stroke
				(width 0.1)
				(type default)
			)
			(layer "F.Fab")
		)
		(fp_line
			(start -0.67945 -0.305054)
			(end -0.12065 -0.305054)
			(stroke
				(width 0.1)
				(type default)
			)
			(layer "F.Fab")
		)
		(fp_line
			(start -0.12065 -0.305054)
			(end -0.12065 -0.2794)
			(stroke
				(width 0.1)
				(type default)
			)
			(layer "F.Fab")
		)
		(pad "1" smd circle
			(at -0.40005 0 270)
			(size 0 0)
			(layers "F.Cu" "F.Mask" "F.Paste")
			(net "GND")
		)
		(pad "2" smd circle
			(at 0.40005 0 270)
			(size 0 0)
			(layers "F.Cu" "F.Mask" "F.Paste")
			(net "SSD9_PWRDIS_BIC_R")
		)
	)
)
